# S9S_MB_2U (Grand Teton) — schematic netlist excerpt (pin names and nets, part order shuffled) for the footprints in the layout excerpt that follows; sources: Cadence DE-HDL packaged netlist, KiCad conversion of 03242023_DA0F0TMBIJ0_F0T_Motherboard_J_brd_V01_OCP.brd

R934  Q_RES  10K 1% CHIP  pkg 0402LF  page 128 : A = RST_CPU0_DRAM_CD_N ; B = GND
R4177  Q_RES  0 5% CHIP  pkg 0402LF  page 257 : A = FM_ESPI_PLD_R_EN_BUF_R ; B = FM_ESPI_PLD_R_EN_BUF

(kicad_pcb
	(version 20260206)
	(generator "pcbnew")
	(generator_version "10.0")
	(general
		(thickness 1.6)
		(legacy_teardrops no)
	)
	(paper "A4")
	(title_block
		(title "03242023_DA0F0TMBIJ0_F0T_Motherboard_J_brd_V01_OCP.brd")
		(comment 1 "Grand Teton / footprints 1423-1424 of 6105")
	)
	(layers
		(0 "F.Cu" signal "TOP")
		(4 "In1.Cu" signal "GND")
		(6 "In2.Cu" signal "IN1")
		(8 "In3.Cu" signal "GND1")
		(10 "In4.Cu" signal "IN2")
		(12 "In5.Cu" signal "GND2")
		(14 "In6.Cu" signal "IN3")
		(16 "In7.Cu" signal "GND3")
		(18 "In8.Cu" signal "VCC")
		(20 "In9.Cu" signal "VCC1")
		(22 "In10.Cu" signal "GND4")
		(24 "In11.Cu" signal "IN4")
		(26 "In12.Cu" signal "GND5")
		(28 "In13.Cu" signal "IN5")
		(30 "In14.Cu" signal "GND6")
		(32 "In15.Cu" signal "IN6")
		(34 "In16.Cu" signal "GND7")
		(2 "B.Cu" signal "BOTTOM")
		(9 "F.Adhes" user "F.Adhesive")
		(11 "B.Adhes" user "B.Adhesive")
		(13 "F.Paste" user "Package Geometry/Pastemask Top")
		(15 "B.Paste" user "Package Geometry/Pastemask Bottom")
		(5 "F.SilkS" user "Ref Des/Silkscreen Top")
		(7 "B.SilkS" user "Ref Des/Silkscreen Bottom")
		(1 "F.Mask" user "Board Geometry/Soldermask Top")
		(3 "B.Mask" user "Board Geometry/Soldermask Bottom")
		(17 "Dwgs.User" user "User.Drawings")
		(19 "Cmts.User" user "User.Comments")
		(21 "Eco1.User" user "User.Eco1")
		(23 "Eco2.User" user "User.Eco2")
		(25 "Edge.Cuts" user "Board Geometry/Outline")
		(27 "Margin" user)
		(31 "F.CrtYd" user "Package Geometry/Place Bound Top")
		(29 "B.CrtYd" user "Package Geometry/Place Bound Bottom")
		(35 "F.Fab" user "Ref Des/Assembly Top")
		(33 "B.Fab" user "Ref Des/Assembly Bottom")
	)
	(footprint ""
		(layer "F.Cu")
		(at 166.01694 -30.584648)
		(property "Reference" "R4177"
			(at 0 0 0)
			(layer "F.SilkS")
			(hide yes)
			(effects
				(font
					(size 1.27 1.27)
				)
			)
		)
		(property "Value" ""
			(at 0 0 0)
			(layer "F.Fab")
			(effects
				(font
					(size 1.27 1.27)
				)
			)
		)
		(duplicate_pad_numbers_are_jumpers no)
		(fp_line
			(start -0.7874 -0.4064)
			(end 0.7874 -0.4064)
			(stroke
				(width 0.1524)
				(type default)
			)
			(layer "F.SilkS")
		)
		(fp_line
			(start -0.7874 0.4064)
			(end -0.7874 -0.4064)
			(stroke
				(width 0.1524)
				(type default)
			)
			(layer "F.SilkS")
		)
		(fp_line
			(start 0.7874 -0.4064)
			(end 0.7874 0.4064)
			(stroke
				(width 0.1524)
				(type default)
			)
			(layer "F.SilkS")
		)
		(fp_line
			(start 0.7874 0.4064)
			(end -0.7874 0.4064)
			(stroke
				(width 0.1524)
				(type default)
			)
			(layer "F.SilkS")
		)
		(fp_line
			(start -0.67945 -0.305054)
			(end -0.12065 -0.305054)
			(stroke
				(width 0.1)
				(type default)
			)
			(layer "F.Fab")
		)
		(fp_line
			(start -0.67945 0.3048)
			(end -0.67945 -0.305054)
			(stroke
				(width 0.1)
				(type default)
			)
			(layer "F.Fab")
		)
		(fp_line
			(start -0.12065 -0.305054)
			(end -0.12065 -0.2794)
			(stroke
				(width 0.1)
				(type default)
			)
			(layer "F.Fab")
		)
		(fp_line
			(start -0.12065 -0.2794)
			(end 0.12065 -0.2794)
			(stroke
				(width 0.1)
				(type default)
			)
			(layer "F.Fab")
		)
		(fp_line
			(start -0.12065 0.2794)
			(end -0.12065 0.3048)
			(stroke
				(width 0.1)
				(type default)
			)
			(layer "F.Fab")
		)
		(fp_line
			(start -0.12065 0.3048)
			(end -0.67945 0.3048)
			(stroke
				(width 0.1)
				(type default)
			)
			(layer "F.Fab")
		)
		(fp_line
			(start 0.120396 0.2794)
			(end -0.12065 0.2794)
			(stroke
				(width 0.1)
				(type default)
			)
			(layer "F.Fab")
		)
		(fp_line
			(start 0.120396 0.3048)
			(end 0.120396 0.2794)
			(stroke
				(width 0.1)
				(type default)
			)
			(layer "F.Fab")
		)
		(fp_line
			(start 0.12065 -0.3048)
			(end 0.67945 -0.3048)
			(stroke
				(width 0.1)
				(type default)
			)
			(layer "F.Fab")
		)
		(fp_line
			(start 0.12065 -0.2794)
			(end 0.12065 -0.3048)
			(stroke
				(width 0.1)
				(type default)
			)
			(layer "F.Fab")
		)
		(fp_line
			(start 0.67945 -0.3048)
			(end 0.67945 0.3048)
			(stroke
				(width 0.1)
				(type default)
			)
			(layer "F.Fab")
		)
		(fp_line
			(start 0.67945 0.3048)
			(end 0.120396 0.3048)
			(stroke
				(width 0.1)
				(type default)
			)
			(layer "F.Fab")
		)
		(pad "1" smd circle
			(at -0.40005 0)
			(size 0 0)
			(layers "F.Cu" "F.Mask" "F.Paste")
			(net "FM_ESPI_PLD_R_EN_BUF_R")
		)
		(pad "2" smd circle
			(at 0.40005 0)
			(size 0 0)
			(layers "F.Cu" "F.Mask" "F.Paste")
			(net "FM_ESPI_PLD_R_EN_BUF")
		)
	)
	(footprint ""
		(layer "F.Cu")
		(at 112.40008 -122.132598 90)
		(property "Reference" "R934"
			(at 0 0 90)
			(layer "F.SilkS")
			(hide yes)
			(effects
				(font
					(size 1.27 1.27)
				)
			)
		)
		(property "Value" ""
			(at 0 0 90)
			(layer "F.Fab")
			(effects
				(font
					(size 1.27 1.27)
				)
			)
		)
		(duplicate_pad_numbers_are_jumpers no)
		(fp_line
			(start 0.7874 -0.4064)
			(end 0.7874 0.4064)
			(stroke
				(width 0.1524)
				(type default)
			)
			(layer "F.SilkS")
		)
		(fp_line
			(start -0.7874 -0.4064)
			(end 0.7874 -0.4064)
			(stroke
				(width 0.1524)
				(type default)
			)
			(layer "F.SilkS")
		)
		(fp_line
			(start 0.7874 0.4064)
			(end -0.7874 0.4064)
			(stroke
				(width 0.1524)
				(type default)
			)
			(layer "F.SilkS")
		)
		(fp_line
			(start -0.7874 0.4064)
			(end -0.7874 -0.4064)
			(stroke
				(width 0.1524)
				(type default)
			)
			(layer "F.SilkS")
		)
		(fp_line
			(start -0.12065 -0.305054)
			(end -0.12065 -0.2794)
			(stroke
				(width 0.1)
				(type default)
			)
			(layer "F.Fab")
		)
		(fp_line
			(start -0.67945 -0.305054)
			(end -0.12065 -0.305054)
			(stroke
				(width 0.1)
				(type default)
			)
			(layer "F.Fab")
		)
		(fp_line
			(start 0.67945 -0.3048)
			(end 0.67945 0.3048)
			(stroke
				(width 0.1)
				(type default)
			)
			(layer "F.Fab")
		)
		(fp_line
			(start 0.12065 -0.3048)
			(end 0.67945 -0.3048)
			(stroke
				(width 0.1)
				(type default)
			)
			(layer "F.Fab")
		)
		(fp_line
			(start 0.12065 -0.2794)
			(end 0.12065 -0.3048)
			(stroke
				(width 0.1)
				(type default)
			)
			(layer "F.Fab")
		)
		(fp_line
			(start -0.12065 -0.2794)
			(end 0.12065 -0.2794)
			(stroke
				(width 0.1)
				(type default)
			)
			(layer "F.Fab")
		)
		(fp_line
			(start 0.120396 0.2794)
			(end -0.12065 0.2794)
			(stroke
				(width 0.1)
				(type default)
			)
			(layer "F.Fab")
		)
		(fp_line
			(start -0.12065 0.2794)
			(end -0.12065 0.3048)
			(stroke
				(width 0.1)
				(type default)
			)
			(layer "F.Fab")
		)
		(fp_line
			(start 0.67945 0.3048)
			(end 0.120396 0.3048)
			(stroke
				(width 0.1)
				(type default)
			)
			(layer "F.Fab")
		)
		(fp_line
			(start 0.120396 0.3048)
			(end 0.120396 0.2794)
			(stroke
				(width 0.1)
				(type default)
			)
			(layer "F.Fab")
		)
		(fp_line
			(start -0.12065 0.3048)
			(end -0.67945 0.3048)
			(stroke
				(width 0.1)
				(type default)
			)
			(layer "F.Fab")
		)
		(fp_line
			(start -0.67945 0.3048)
			(end -0.67945 -0.305054)
			(stroke
				(width 0.1)
				(type default)
			)
			(layer "F.Fab")
		)
		(pad "1" smd circle
			(at -0.40005 0 90)
			(size 0 0)
			(layers "F.Cu" "F.Mask" "F.Paste")
			(net "RST_CPU0_DRAM_CD_N")
		)
		(pad "2" smd circle
			(at 0.40005 0 90)
			(size 0 0)
			(layers "F.Cu" "F.Mask" "F.Paste")
			(net "GND")
		)
	)
)
